# SCM (Grand Teton) — schematic netlist excerpt (pin names and nets, part order shuffled) for the footprints in the layout excerpt that follows; sources: Cadence DE-HDL packaged netlist, KiCad conversion of 12092022_DA0F0TMDCD0_F0T_Management_Board_D_brd_V3_OCP.brd

R380  Q_RES  100 1% CHIP  pkg 0402LF  page 52 : A = EN_P3V3_RGM ; B = EN_P3V3_RGM_R
R877  Q_RES  0 5% EMPTY  pkg 0402LF  page 55 : A = PWRGD_P1V2_AUX_R ; B = PWRGD_P1V2_AUX_R2

(kicad_pcb
	(version 20260206)
	(generator "pcbnew")
	(generator_version "10.0")
	(general
		(thickness 1.6)
		(legacy_teardrops no)
	)
	(paper "A4")
	(title_block
		(title "12092022_DA0F0TMDCD0_F0T_Management_Board_D_brd_V3_OCP.brd")
		(comment 1 "Grand Teton / footprints 469-470 of 1440")
	)
	(layers
		(0 "F.Cu" signal "TOP")
		(4 "In1.Cu" signal "GND")
		(6 "In2.Cu" signal "IN1")
		(8 "In3.Cu" signal "GND1")
		(10 "In4.Cu" signal "IN2")
		(12 "In5.Cu" signal "VCC")
		(14 "In6.Cu" signal "VCC1")
		(16 "In7.Cu" signal "IN3")
		(18 "In8.Cu" signal "GND2")
		(20 "In9.Cu" signal "IN4")
		(22 "In10.Cu" signal "GND3")
		(2 "B.Cu" signal "BOTTOM")
		(9 "F.Adhes" user "F.Adhesive")
		(11 "B.Adhes" user "B.Adhesive")
		(13 "F.Paste" user "Package Geometry/Pastemask Top")
		(15 "B.Paste" user "Package Geometry/Pastemask Bottom")
		(5 "F.SilkS" user "Ref Des/Silkscreen Top")
		(7 "B.SilkS" user "Ref Des/Silkscreen Bottom")
		(1 "F.Mask" user "Board Geometry/Soldermask Top")
		(3 "B.Mask" user "Board Geometry/Soldermask Bottom")
		(17 "Dwgs.User" user "User.Drawings")
		(19 "Cmts.User" user "User.Comments")
		(21 "Eco1.User" user "User.Eco1")
		(23 "Eco2.User" user "User.Eco2")
		(25 "Edge.Cuts" user "Board Geometry/Outline")
		(27 "Margin" user)
		(31 "F.CrtYd" user "Package Geometry/Place Bound Top")
		(29 "B.CrtYd" user "Package Geometry/Place Bound Bottom")
		(35 "F.Fab" user "Ref Des/Assembly Top")
		(33 "B.Fab" user "Ref Des/Assembly Bottom")
	)
	(footprint ""
		(layer "F.Cu")
		(at 67.5386 -28.321 90)
		(property "Reference" "R380"
			(at 0 0 90)
			(layer "F.SilkS")
			(hide yes)
			(effects
				(font
					(size 1.27 1.27)
				)
			)
		)
		(property "Value" ""
			(at 0 0 90)
			(layer "F.Fab")
			(effects
				(font
					(size 1.27 1.27)
				)
			)
		)
		(duplicate_pad_numbers_are_jumpers no)
		(fp_line
			(start 0.7874 -0.4064)
			(end 0.7874 0.4064)
			(stroke
				(width 0.1524)
				(type default)
			)
			(layer "F.SilkS")
		)
		(fp_line
			(start -0.7874 -0.4064)
			(end 0.7874 -0.4064)
			(stroke
				(width 0.1524)
				(type default)
			)
			(layer "F.SilkS")
		)
		(fp_line
			(start 0.7874 0.4064)
			(end -0.7874 0.4064)
			(stroke
				(width 0.1524)
				(type default)
			)
			(layer "F.SilkS")
		)
		(fp_line
			(start -0.7874 0.4064)
			(end -0.7874 -0.4064)
			(stroke
				(width 0.1524)
				(type default)
			)
			(layer "F.SilkS")
		)
		(fp_line
			(start -0.12065 -0.305054)
			(end -0.12065 -0.2794)
			(stroke
				(width 0.1)
				(type default)
			)
			(layer "F.Fab")
		)
		(fp_line
			(start -0.67945 -0.305054)
			(end -0.12065 -0.305054)
			(stroke
				(width 0.1)
				(type default)
			)
			(layer "F.Fab")
		)
		(fp_line
			(start 0.67945 -0.3048)
			(end 0.67945 0.3048)
			(stroke
				(width 0.1)
				(type default)
			)
			(layer "F.Fab")
		)
		(fp_line
			(start 0.12065 -0.3048)
			(end 0.67945 -0.3048)
			(stroke
				(width 0.1)
				(type default)
			)
			(layer "F.Fab")
		)
		(fp_line
			(start 0.12065 -0.2794)
			(end 0.12065 -0.3048)
			(stroke
				(width 0.1)
				(type default)
			)
			(layer "F.Fab")
		)
		(fp_line
			(start -0.12065 -0.2794)
			(end 0.12065 -0.2794)
			(stroke
				(width 0.1)
				(type default)
			)
			(layer "F.Fab")
		)
		(fp_line
			(start 0.120396 0.2794)
			(end -0.12065 0.2794)
			(stroke
				(width 0.1)
				(type default)
			)
			(layer "F.Fab")
		)
		(fp_line
			(start -0.12065 0.2794)
			(end -0.12065 0.3048)
			(stroke
				(width 0.1)
				(type default)
			)
			(layer "F.Fab")
		)
		(fp_line
			(start 0.67945 0.3048)
			(end 0.120396 0.3048)
			(stroke
				(width 0.1)
				(type default)
			)
			(layer "F.Fab")
		)
		(fp_line
			(start 0.120396 0.3048)
			(end 0.120396 0.2794)
			(stroke
				(width 0.1)
				(type default)
			)
			(layer "F.Fab")
		)
		(fp_line
			(start -0.12065 0.3048)
			(end -0.67945 0.3048)
			(stroke
				(width 0.1)
				(type default)
			)
			(layer "F.Fab")
		)
		(fp_line
			(start -0.67945 0.3048)
			(end -0.67945 -0.305054)
			(stroke
				(width 0.1)
				(type default)
			)
			(layer "F.Fab")
		)
		(pad "1" smd circle
			(at -0.40005 0 90)
			(size 0 0)
			(layers "F.Cu" "F.Mask" "F.Paste")
			(net "EN_P3V3_RGM")
		)
		(pad "2" smd circle
			(at 0.40005 0 90)
			(size 0 0)
			(layers "F.Cu" "F.Mask" "F.Paste")
			(net "EN_P3V3_RGM_R")
		)
	)
	(footprint ""
		(layer "F.Cu")
		(at 85.471 -76.6572 90)
		(property "Reference" "R877"
			(at 0 0 90)
			(layer "F.SilkS")
			(hide yes)
			(effects
				(font
					(size 1.27 1.27)
				)
			)
		)
		(property "Value" ""
			(at 0 0 90)
			(layer "F.Fab")
			(effects
				(font
					(size 1.27 1.27)
				)
			)
		)
		(duplicate_pad_numbers_are_jumpers no)
		(fp_line
			(start 0.7874 -0.4064)
			(end 0.7874 0.4064)
			(stroke
				(width 0.1524)
				(type default)
			)
			(layer "F.SilkS")
		)
		(fp_line
			(start -0.7874 -0.4064)
			(end 0.7874 -0.4064)
			(stroke
				(width 0.1524)
				(type default)
			)
			(layer "F.SilkS")
		)
		(fp_line
			(start 0.7874 0.4064)
			(end -0.7874 0.4064)
			(stroke
				(width 0.1524)
				(type default)
			)
			(layer "F.SilkS")
		)
		(fp_line
			(start -0.7874 0.4064)
			(end -0.7874 -0.4064)
			(stroke
				(width 0.1524)
				(type default)
			)
			(layer "F.SilkS")
		)
		(fp_line
			(start -0.12065 -0.305054)
			(end -0.12065 -0.2794)
			(stroke
				(width 0.1)
				(type default)
			)
			(layer "F.Fab")
		)
		(fp_line
			(start -0.67945 -0.305054)
			(end -0.12065 -0.305054)
			(stroke
				(width 0.1)
				(type default)
			)
			(layer "F.Fab")
		)
		(fp_line
			(start 0.67945 -0.3048)
			(end 0.67945 0.3048)
			(stroke
				(width 0.1)
				(type default)
			)
			(layer "F.Fab")
		)
		(fp_line
			(start 0.12065 -0.3048)
			(end 0.67945 -0.3048)
			(stroke
				(width 0.1)
				(type default)
			)
			(layer "F.Fab")
		)
		(fp_line
			(start 0.12065 -0.2794)
			(end 0.12065 -0.3048)
			(stroke
				(width 0.1)
				(type default)
			)
			(layer "F.Fab")
		)
		(fp_line
			(start -0.12065 -0.2794)
			(end 0.12065 -0.2794)
			(stroke
				(width 0.1)
				(type default)
			)
			(layer "F.Fab")
		)
		(fp_line
			(start 0.120396 0.2794)
			(end -0.12065 0.2794)
			(stroke
				(width 0.1)
				(type default)
			)
			(layer "F.Fab")
		)
		(fp_line
			(start -0.12065 0.2794)
			(end -0.12065 0.3048)
			(stroke
				(width 0.1)
				(type default)
			)
			(layer "F.Fab")
		)
		(fp_line
			(start 0.67945 0.3048)
			(end 0.120396 0.3048)
			(stroke
				(width 0.1)
				(type default)
			)
			(layer "F.Fab")
		)
		(fp_line
			(start 0.120396 0.3048)
			(end 0.120396 0.2794)
			(stroke
				(width 0.1)
				(type default)
			)
			(layer "F.Fab")
		)
		(fp_line
			(start -0.12065 0.3048)
			(end -0.67945 0.3048)
			(stroke
				(width 0.1)
				(type default)
			)
			(layer "F.Fab")
		)
		(fp_line
			(start -0.67945 0.3048)
			(end -0.67945 -0.305054)
			(stroke
				(width 0.1)
				(type default)
			)
			(layer "F.Fab")
		)
		(pad "1" smd circle
			(at -0.40005 0 90)
			(size 0 0)
			(layers "F.Cu" "F.Mask" "F.Paste")
			(net "PWRGD_P1V2_AUX_R")
		)
		(pad "2" smd circle
			(at 0.40005 0 90)
			(size 0 0)
			(layers "F.Cu" "F.Mask" "F.Paste")
			(net "PWRGD_P1V2_AUX_R2")
		)
	)
)
